# T6G (Grand Teton) — schematic netlist excerpt (pin names and nets, part order shuffled) for the footprints in the layout excerpt that follows; sources: Cadence DE-HDL packaged netlist, KiCad conversion of 04192023_DAF0TMB3IC0_F0TG_MB_C_brd_V02_OCP.brd

R3946  Q_RES  0 5% CHIP  pkg 0402LF  page 147 : A = E1S_0_P3V3_EN ; B = P3V3_E1S_EN_0_R2
PC2200  Q_CAP  1UF 25V 10% X6S  pkg C0402  page 147 : A = P3V3_AUX ; B = GND
C679  Q_CAP_DIFFBUS  DIFF BUS_0.22UF 6.3V 20% X6S  pkg C0201  page 67 : \1\ = P5E_CPU1_G1_TX_C_DP<15> ; \2\ = P5E_CPU1_G1_TX_DP<15>

(kicad_pcb
	(version 20260206)
	(generator "pcbnew")
	(generator_version "10.0")
	(general
		(thickness 1.6)
		(legacy_teardrops no)
	)
	(paper "A4")
	(title_block
		(title "04192023_DAF0TMB3IC0_F0TG_MB_C_brd_V02_OCP.brd")
		(comment 1 "Grand Teton / footprints 4447-4449 of 8354")
	)
	(layers
		(0 "F.Cu" signal "TOP")
		(4 "In1.Cu" signal "GND")
		(6 "In2.Cu" signal "IN1")
		(8 "In3.Cu" signal "GND1")
		(10 "In4.Cu" signal "IN2")
		(12 "In5.Cu" signal "GND2")
		(14 "In6.Cu" signal "IN3")
		(16 "In7.Cu" signal "GND3")
		(18 "In8.Cu" signal "VCC")
		(20 "In9.Cu" signal "VCC1")
		(22 "In10.Cu" signal "GND4")
		(24 "In11.Cu" signal "IN4")
		(26 "In12.Cu" signal "GND5")
		(28 "In13.Cu" signal "IN5")
		(30 "In14.Cu" signal "GND6")
		(32 "In15.Cu" signal "IN6")
		(34 "In16.Cu" signal "GND7")
		(2 "B.Cu" signal "BOTTOM")
		(9 "F.Adhes" user "F.Adhesive")
		(11 "B.Adhes" user "B.Adhesive")
		(13 "F.Paste" user "Package Geometry/Pastemask Top")
		(15 "B.Paste" user "Package Geometry/Pastemask Bottom")
		(5 "F.SilkS" user "Ref Des/Silkscreen Top")
		(7 "B.SilkS" user "Ref Des/Silkscreen Bottom")
		(1 "F.Mask" user "Board Geometry/Soldermask Top")
		(3 "B.Mask" user "Board Geometry/Soldermask Bottom")
		(17 "Dwgs.User" user "User.Drawings")
		(19 "Cmts.User" user "User.Comments")
		(21 "Eco1.User" user "User.Eco1")
		(23 "Eco2.User" user "User.Eco2")
		(25 "Edge.Cuts" user "Board Geometry/Outline")
		(27 "Margin" user)
		(31 "F.CrtYd" user "Package Geometry/Place Bound Top")
		(29 "B.CrtYd" user "Package Geometry/Place Bound Bottom")
		(35 "F.Fab" user "Ref Des/Assembly Top")
		(33 "B.Fab" user "Ref Des/Assembly Bottom")
	)
	(footprint ""
		(layer "F.Cu")
		(at 196.536564 -71.836788 90)
		(property "Reference" "PC2200"
			(at 0 0 90)
			(layer "F.SilkS")
			(hide yes)
			(effects
				(font
					(size 1.27 1.27)
				)
			)
		)
		(property "Value" ""
			(at 0 0 90)
			(layer "F.Fab")
			(effects
				(font
					(size 1.27 1.27)
				)
			)
		)
		(duplicate_pad_numbers_are_jumpers no)
		(fp_line
			(start 0.7874 -0.4064)
			(end 0.7874 0.4064)
			(stroke
				(width 0.1524)
				(type default)
			)
			(layer "F.SilkS")
		)
		(fp_line
			(start -0.7874 -0.4064)
			(end 0.7874 -0.4064)
			(stroke
				(width 0.1524)
				(type default)
			)
			(layer "F.SilkS")
		)
		(fp_line
			(start 0.7874 0.4064)
			(end -0.7874 0.4064)
			(stroke
				(width 0.1524)
				(type default)
			)
			(layer "F.SilkS")
		)
		(fp_line
			(start -0.7874 0.4064)
			(end -0.7874 -0.4064)
			(stroke
				(width 0.1524)
				(type default)
			)
			(layer "F.SilkS")
		)
		(fp_line
			(start -0.12065 -0.305054)
			(end -0.12065 -0.2794)
			(stroke
				(width 0.1)
				(type default)
			)
			(layer "F.Fab")
		)
		(fp_line
			(start -0.67945 -0.305054)
			(end -0.12065 -0.305054)
			(stroke
				(width 0.1)
				(type default)
			)
			(layer "F.Fab")
		)
		(fp_line
			(start 0.67945 -0.3048)
			(end 0.67945 0.3048)
			(stroke
				(width 0.1)
				(type default)
			)
			(layer "F.Fab")
		)
		(fp_line
			(start 0.12065 -0.3048)
			(end 0.67945 -0.3048)
			(stroke
				(width 0.1)
				(type default)
			)
			(layer "F.Fab")
		)
		(fp_line
			(start 0.12065 -0.2794)
			(end 0.12065 -0.3048)
			(stroke
				(width 0.1)
				(type default)
			)
			(layer "F.Fab")
		)
		(fp_line
			(start -0.12065 -0.2794)
			(end 0.12065 -0.2794)
			(stroke
				(width 0.1)
				(type default)
			)
			(layer "F.Fab")
		)
		(fp_line
			(start 0.120396 0.2794)
			(end -0.12065 0.2794)
			(stroke
				(width 0.1)
				(type default)
			)
			(layer "F.Fab")
		)
		(fp_line
			(start -0.12065 0.2794)
			(end -0.12065 0.3048)
			(stroke
				(width 0.1)
				(type default)
			)
			(layer "F.Fab")
		)
		(fp_line
			(start 0.67945 0.3048)
			(end 0.120396 0.3048)
			(stroke
				(width 0.1)
				(type default)
			)
			(layer "F.Fab")
		)
		(fp_line
			(start 0.120396 0.3048)
			(end 0.120396 0.2794)
			(stroke
				(width 0.1)
				(type default)
			)
			(layer "F.Fab")
		)
		(fp_line
			(start -0.12065 0.3048)
			(end -0.67945 0.3048)
			(stroke
				(width 0.1)
				(type default)
			)
			(layer "F.Fab")
		)
		(fp_line
			(start -0.67945 0.3048)
			(end -0.67945 -0.305054)
			(stroke
				(width 0.1)
				(type default)
			)
			(layer "F.Fab")
		)
		(pad "1" smd circle
			(at -0.40005 0 90)
			(size 0 0)
			(layers "F.Cu" "F.Mask" "F.Paste")
			(net "P3V3_AUX")
		)
		(pad "2" smd circle
			(at 0.40005 0 90)
			(size 0 0)
			(layers "F.Cu" "F.Mask" "F.Paste")
			(net "GND")
		)
	)
	(footprint ""
		(layer "F.Cu")
		(at 16.422878 -16.099536 90)
		(property "Reference" "C679"
			(at 0 0 90)
			(layer "F.SilkS")
			(hide yes)
			(effects
				(font
					(size 1.27 1.27)
				)
			)
		)
		(property "Value" ""
			(at 0 0 90)
			(layer "F.Fab")
			(effects
				(font
					(size 1.27 1.27)
				)
			)
		)
		(duplicate_pad_numbers_are_jumpers no)
		(fp_line
			(start 0.299974 -0.150114)
			(end 0.299974 0.150114)
			(stroke
				(width 0.1)
				(type default)
			)
			(layer "F.Fab")
		)
		(fp_line
			(start -0.299974 -0.150114)
			(end 0.299974 -0.150114)
			(stroke
				(width 0.1)
				(type default)
			)
			(layer "F.Fab")
		)
		(fp_line
			(start 0.299974 0.150114)
			(end -0.299974 0.150114)
			(stroke
				(width 0.1)
				(type default)
			)
			(layer "F.Fab")
		)
		(fp_line
			(start -0.299974 0.150114)
			(end -0.299974 -0.150114)
			(stroke
				(width 0.1)
				(type default)
			)
			(layer "F.Fab")
		)
		(pad "1" smd rect
			(at -0.2667 0 90)
			(size 0.3048 0.381)
			(layers "F.Cu" "F.Mask" "F.Paste")
			(net "P5E_CPU1_G1_TX_C_DP<15>")
		)
		(pad "2" smd rect
			(at 0.2667 0 90)
			(size 0.3048 0.381)
			(layers "F.Cu" "F.Mask" "F.Paste")
			(net "P5E_CPU1_G1_TX_DP<15>")
		)
	)
	(footprint ""
		(layer "F.Cu")
		(at 200.600564 -69.804788 180)
		(property "Reference" "R3946"
			(at 0 0 180)
			(layer "F.SilkS")
			(hide yes)
			(effects
				(font
					(size 1.27 1.27)
				)
			)
		)
		(property "Value" ""
			(at 0 0 180)
			(layer "F.Fab")
			(effects
				(font
					(size 1.27 1.27)
				)
			)
		)
		(duplicate_pad_numbers_are_jumpers no)
		(fp_line
			(start 0.7874 0.4064)
			(end -0.7874 0.4064)
			(stroke
				(width 0.1524)
				(type default)
			)
			(layer "F.SilkS")
		)
		(fp_line
			(start 0.7874 -0.4064)
			(end 0.7874 0.4064)
			(stroke
				(width 0.1524)
				(type default)
			)
			(layer "F.SilkS")
		)
		(fp_line
			(start -0.7874 0.4064)
			(end -0.7874 -0.4064)
			(stroke
				(width 0.1524)
				(type default)
			)
			(layer "F.SilkS")
		)
		(fp_line
			(start -0.7874 -0.4064)
			(end 0.7874 -0.4064)
			(stroke
				(width 0.1524)
				(type default)
			)
			(layer "F.SilkS")
		)
		(fp_line
			(start 0.67945 0.3048)
			(end 0.120396 0.3048)
			(stroke
				(width 0.1)
				(type default)
			)
			(layer "F.Fab")
		)
		(fp_line
			(start 0.67945 -0.3048)
			(end 0.67945 0.3048)
			(stroke
				(width 0.1)
				(type default)
			)
			(layer "F.Fab")
		)
		(fp_line
			(start 0.12065 -0.2794)
			(end 0.12065 -0.3048)
			(stroke
				(width 0.1)
				(type default)
			)
			(layer "F.Fab")
		)
		(fp_line
			(start 0.12065 -0.3048)
			(end 0.67945 -0.3048)
			(stroke
				(width 0.1)
				(type default)
			)
			(layer "F.Fab")
		)
		(fp_line
			(start 0.120396 0.3048)
			(end 0.120396 0.2794)
			(stroke
				(width 0.1)
				(type default)
			)
			(layer "F.Fab")
		)
		(fp_line
			(start 0.120396 0.2794)
			(end -0.12065 0.2794)
			(stroke
				(width 0.1)
				(type default)
			)
			(layer "F.Fab")
		)
		(fp_line
			(start -0.12065 0.3048)
			(end -0.67945 0.3048)
			(stroke
				(width 0.1)
				(type default)
			)
			(layer "F.Fab")
		)
		(fp_line
			(start -0.12065 0.2794)
			(end -0.12065 0.3048)
			(stroke
				(width 0.1)
				(type default)
			)
			(layer "F.Fab")
		)
		(fp_line
			(start -0.12065 -0.2794)
			(end 0.12065 -0.2794)
			(stroke
				(width 0.1)
				(type default)
			)
			(layer "F.Fab")
		)
		(fp_line
			(start -0.12065 -0.305054)
			(end -0.12065 -0.2794)
			(stroke
				(width 0.1)
				(type default)
			)
			(layer "F.Fab")
		)
		(fp_line
			(start -0.67945 0.3048)
			(end -0.67945 -0.305054)
			(stroke
				(width 0.1)
				(type default)
			)
			(layer "F.Fab")
		)
		(fp_line
			(start -0.67945 -0.305054)
			(end -0.12065 -0.305054)
			(stroke
				(width 0.1)
				(type default)
			)
			(layer "F.Fab")
		)
		(pad "1" smd circle
			(at -0.40005 0 180)
			(size 0 0)
			(layers "F.Cu" "F.Mask" "F.Paste")
			(net "E1S_0_P3V3_EN")
		)
		(pad "2" smd circle
			(at 0.40005 0 180)
			(size 0 0)
			(layers "F.Cu" "F.Mask" "F.Paste")
			(net "P3V3_E1S_EN_0_R2")
		)
	)
)
